# BASEBOARD_FAB2 (Tioga Pass) — schematic netlist excerpt (pin names and nets, part order shuffled) for the footprints in the layout excerpt that follows; sources: Cadence DE-HDL packaged netlist, KiCad conversion of Wiwynn_Tioga_Pass_MB.brd

C6R16  CAPP  470UF 2.5V 20% ALUM  pkg 3018  page 193 : A = PVCCMCP_CPU1 ; B = GND
R25W131  RES  4.75K 1% CHIP  pkg 0402  page 252 : A = P3V3 ; B = Q25W1_GATE
C3L4  CAP  10UF 16V 10% X6S  pkg 0805  page 219 : A = VR_FET_SW_P12V_STBY_PVDDQ_DEF ; B = GND

(kicad_pcb
	(version 20260206)
	(generator "pcbnew")
	(generator_version "10.0")
	(general
		(thickness 1.6)
		(legacy_teardrops no)
	)
	(paper "A4")
	(title_block
		(title "Wiwynn_Tioga_Pass_MB.brd")
		(comment 1 "Tioga Pass / footprints 3203-3205 of 4770")
	)
	(layers
		(0 "F.Cu" signal "TOP")
		(4 "In1.Cu" signal "L2GND")
		(6 "In2.Cu" signal "L3")
		(8 "In3.Cu" signal "L4GND")
		(10 "In4.Cu" signal "L5")
		(12 "In5.Cu" signal "L6GND")
		(14 "In6.Cu" signal "L7VCC")
		(16 "In7.Cu" signal "L8VCC")
		(18 "In8.Cu" signal "L9GND")
		(20 "In9.Cu" signal "L10")
		(22 "In10.Cu" signal "L11GND")
		(24 "In11.Cu" signal "L12")
		(26 "In12.Cu" signal "L13GND")
		(2 "B.Cu" signal "BOTTOM")
		(9 "F.Adhes" user "F.Adhesive")
		(11 "B.Adhes" user "B.Adhesive")
		(13 "F.Paste" user "Package Geometry/Pastemask Top")
		(15 "B.Paste" user "Package Geometry/Pastemask Bottom")
		(5 "F.SilkS" user "Ref Des/Silkscreen Top")
		(7 "B.SilkS" user "Ref Des/Silkscreen Bottom")
		(1 "F.Mask" user "Board Geometry/Soldermask Top")
		(3 "B.Mask" user "Board Geometry/Soldermask Bottom")
		(17 "Dwgs.User" user "User.Drawings")
		(19 "Cmts.User" user "User.Comments")
		(21 "Eco1.User" user "User.Eco1")
		(23 "Eco2.User" user "User.Eco2")
		(25 "Edge.Cuts" user "Board Geometry/Outline")
		(27 "Margin" user)
		(31 "F.CrtYd" user "Package Geometry/Place Bound Top")
		(29 "B.CrtYd" user "Package Geometry/Place Bound Bottom")
		(35 "F.Fab" user "Ref Des/Assembly Top")
		(33 "B.Fab" user "Ref Des/Assembly Bottom")
	)
	(footprint ""
		(layer "B.Cu")
		(at 348.615 -146.343624 -90)
		(property "Reference" "C3L4"
			(at 0 0 90)
			(layer "B.SilkS")
			(hide yes)
			(effects
				(font
					(size 1.27 1.27)
				)
				(justify mirror)
			)
		)
		(property "Value" ""
			(at 0 0 90)
			(layer "B.Fab")
			(effects
				(font
					(size 1.27 1.27)
				)
				(justify mirror)
			)
		)
		(duplicate_pad_numbers_are_jumpers no)
		(fp_poly
			(pts
				(xy 0.7239 -0.2159) (xy -0.7239 -0.2159) (xy -0.7239 1.9939) (xy 0.7239 1.9939)
			)
			(stroke
				(width 0)
				(type default)
			)
			(fill no)
			(layer "B.CrtYd")
		)
		(fp_line
			(start -0.7239 1.9939)
			(end -0.7239 -0.2159)
			(stroke
				(width 0.1)
				(type default)
			)
			(layer "B.Fab")
		)
		(fp_line
			(start 0.7239 1.9939)
			(end -0.7239 1.9939)
			(stroke
				(width 0.1)
				(type default)
			)
			(layer "B.Fab")
		)
		(fp_line
			(start -0.7239 -0.2159)
			(end 0.7239 -0.2159)
			(stroke
				(width 0.1)
				(type default)
			)
			(layer "B.Fab")
		)
		(fp_line
			(start 0.7239 -0.2159)
			(end 0.7239 1.9939)
			(stroke
				(width 0.1)
				(type default)
			)
			(layer "B.Fab")
		)
		(pad "1" smd rect
			(at 0 0 90)
			(size 1.27 1.016)
			(layers "B.Cu" "B.Mask" "B.Paste")
			(net "VR_FET_SW_P12V_STBY_PVDDQ_DEF")
		)
		(pad "2" smd rect
			(at 0 1.778 90)
			(size 1.27 1.016)
			(layers "B.Cu" "B.Mask" "B.Paste")
			(net "GND")
		)
		(zone
			(layer "B.Cu")
			(hatch none 0.5)
			(connect_pads
				(clearance 0)
			)
			(min_thickness 0.25)
			(keepout
				(tracks not_allowed)
				(vias allowed)
				(pads allowed)
				(copperpour not_allowed)
				(footprints allowed)
			)
			(placement
				(enabled no)
				(sheetname "")
			)
			(fill
				(thermal_gap 0.5)
				(thermal_bridge_width 0.5)
				(island_removal_mode 0)
			)
			(polygon
				(pts
					(xy 348.107 -145.708624) (xy 348.107 -146.978624) (xy 347.345 -146.978624) (xy 347.345 -145.708624)
				)
			)
		)
	)
	(footprint ""
		(layer "B.Cu")
		(at 185.42 -49.7078 90)
		(property "Reference" "C6R16"
			(at -3.12547 4.191 0)
			(unlocked yes)
			(layer "B.SilkS")
			(effects
				(font
					(size 0.7874 0.5842)
					(thickness 0.1524)
				)
				(justify mirror)
			)
		)
		(property "Value" ""
			(at 0 0 90)
			(layer "B.Fab")
			(effects
				(font
					(size 1.27 1.27)
				)
				(justify mirror)
			)
		)
		(duplicate_pad_numbers_are_jumpers no)
		(fp_line
			(start 2.563114 -1.616456)
			(end 2.563114 1.633728)
			(stroke
				(width 0.1524)
				(type default)
			)
			(layer "B.SilkS")
		)
		(fp_line
			(start 1.6002 -1.616456)
			(end 2.563114 -1.616456)
			(stroke
				(width 0.1524)
				(type default)
			)
			(layer "B.SilkS")
		)
		(fp_line
			(start -1.6002 -1.616456)
			(end -2.504948 -1.616456)
			(stroke
				(width 0.1524)
				(type default)
			)
			(layer "B.SilkS")
		)
		(fp_line
			(start -2.504948 -1.616456)
			(end -2.504948 1.633728)
			(stroke
				(width 0.1524)
				(type default)
			)
			(layer "B.SilkS")
		)
		(fp_line
			(start 2.563114 1.633728)
			(end 1.6002 1.633728)
			(stroke
				(width 0.1524)
				(type default)
			)
			(layer "B.SilkS")
		)
		(fp_line
			(start -2.504948 1.633728)
			(end -1.6002 1.633728)
			(stroke
				(width 0.1524)
				(type default)
			)
			(layer "B.SilkS")
		)
		(fp_line
			(start 2.286 7.366)
			(end 2.286 1.632712)
			(stroke
				(width 0.1524)
				(type default)
			)
			(layer "B.SilkS")
		)
		(fp_line
			(start 2.286 7.366)
			(end 1.60147 7.366)
			(stroke
				(width 0.1524)
				(type default)
			)
			(layer "B.SilkS")
		)
		(fp_line
			(start -2.286 7.366)
			(end -2.286 1.63195)
			(stroke
				(width 0.1524)
				(type default)
			)
			(layer "B.SilkS")
		)
		(fp_line
			(start -2.286 7.366)
			(end -1.600708 7.366)
			(stroke
				(width 0.1524)
				(type default)
			)
			(layer "B.SilkS")
		)
		(fp_rect
			(start 2.286 7.366)
			(end -2.286 -0.254)
			(stroke
				(width 0)
				(type default)
			)
			(fill no)
			(layer "B.CrtYd")
		)
		(fp_line
			(start 2.286 -0.254)
			(end -2.286 -0.254)
			(stroke
				(width 0.1)
				(type default)
			)
			(layer "B.Fab")
		)
		(fp_line
			(start -2.286 -0.254)
			(end -2.286 7.366)
			(stroke
				(width 0.1)
				(type default)
			)
			(layer "B.Fab")
		)
		(fp_line
			(start 2.286 7.366)
			(end 2.286 -0.254)
			(stroke
				(width 0.1)
				(type default)
			)
			(layer "B.Fab")
		)
		(fp_line
			(start -2.286 7.366)
			(end 2.286 7.366)
			(stroke
				(width 0.1)
				(type default)
			)
			(layer "B.Fab")
		)
		(pad "1" smd rect
			(at 0 0 270)
			(size 2.54 3.048)
			(layers "B.Cu" "B.Mask" "B.Paste")
			(net "PVCCMCP_CPU1")
		)
		(pad "2" smd rect
			(at 0 7.112 270)
			(size 2.54 3.048)
			(layers "B.Cu" "B.Mask" "B.Paste")
			(net "GND")
		)
	)
	(footprint ""
		(layer "B.Cu")
		(at 489.445046 -46.665388 90)
		(property "Reference" "R25W131"
			(at 0.8382 -0.67818 90)
			(unlocked yes)
			(layer "B.SilkS")
			(effects
				(font
					(size 0.4064 0.254)
					(thickness 0.1524)
				)
				(justify left mirror)
			)
		)
		(property "Value" ""
			(at 0 0 90)
			(layer "B.Fab")
			(effects
				(font
					(size 1.27 1.27)
				)
				(justify mirror)
			)
		)
		(duplicate_pad_numbers_are_jumpers no)
		(fp_poly
			(pts
				(xy 0.2794 -0.1016) (xy -0.2794 -0.1016) (xy -0.2794 0.9906) (xy 0.2794 0.9906)
			)
			(stroke
				(width 0)
				(type default)
			)
			(fill no)
			(layer "B.CrtYd")
		)
		(fp_line
			(start 0.2794 -0.1016)
			(end 0.2794 0.9906)
			(stroke
				(width 0.1)
				(type default)
			)
			(layer "B.Fab")
		)
		(fp_line
			(start -0.2794 -0.1016)
			(end 0.2794 -0.1016)
			(stroke
				(width 0.1)
				(type default)
			)
			(layer "B.Fab")
		)
		(fp_line
			(start 0.2794 0.9906)
			(end -0.2794 0.9906)
			(stroke
				(width 0.1)
				(type default)
			)
			(layer "B.Fab")
		)
		(fp_line
			(start -0.2794 0.9906)
			(end -0.2794 -0.1016)
			(stroke
				(width 0.1)
				(type default)
			)
			(layer "B.Fab")
		)
		(pad "1" smd rect
			(at 0 0 270)
			(size 0.508 0.508)
			(layers "B.Cu" "B.Mask" "B.Paste")
			(net "P3V3")
		)
		(pad "2" smd rect
			(at 0 0.889 270)
			(size 0.508 0.508)
			(layers "B.Cu" "B.Mask" "B.Paste")
			(net "Q25W1_GATE")
		)
		(zone
			(layer "B.Cu")
			(hatch none 0.5)
			(connect_pads
				(clearance 0)
			)
			(min_thickness 0.25)
			(keepout
				(tracks allowed)
				(vias not_allowed)
				(pads allowed)
				(copperpour not_allowed)
				(footprints allowed)
			)
			(placement
				(enabled no)
				(sheetname "")
			)
			(fill
				(thermal_gap 0.5)
				(thermal_bridge_width 0.5)
				(island_removal_mode 0)
			)
			(polygon
				(pts
					(xy 489.699046 -46.919388) (xy 489.699046 -46.411388) (xy 490.080046 -46.411388) (xy 490.080046 -46.919388)
				)
			)
		)
		(zone
			(layer "B.Cu")
			(hatch none 0.5)
			(connect_pads
				(clearance 0)
			)
			(min_thickness 0.25)
			(keepout
				(tracks not_allowed)
				(vias allowed)
				(pads allowed)
				(copperpour not_allowed)
				(footprints allowed)
			)
			(placement
				(enabled no)
				(sheetname "")
			)
			(fill
				(thermal_gap 0.5)
				(thermal_bridge_width 0.5)
				(island_removal_mode 0)
			)
			(polygon
				(pts
					(xy 490.080046 -46.919388) (xy 490.080046 -46.411388) (xy 489.699046 -46.411388) (xy 489.699046 -46.919388)
				)
			)
		)
	)
)
